(kicad_pcb
	(version 20260206)
	(generator "pcbnew")
	(generator_version "10.0")
	(general
		(thickness 1.6)
		(legacy_teardrops no)
	)
	(paper "A4")
	(title_block
		(title "peb — Lightning_PEB_BRD.brd")
		(comment 1 "Lightning (Wiwynn / Facebook NVMe JBOF) / footprints 1510-1514 of 2563")
	)
	(layers
		(0 "F.Cu" signal "TOP")
		(4 "In1.Cu" signal "L2GND")
		(6 "In2.Cu" signal "L3")
		(8 "In3.Cu" signal "L4VCC")
		(10 "In4.Cu" signal "L5VCC")
		(12 "In5.Cu" signal "L6")
		(14 "In6.Cu" signal "L7GND")
		(2 "B.Cu" signal "BOTTOM")
		(9 "F.Adhes" user "F.Adhesive")
		(11 "B.Adhes" user "B.Adhesive")
		(13 "F.Paste" user "Package Geometry/Pastemask Top")
		(15 "B.Paste" user "Package Geometry/Pastemask Bottom")
		(5 "F.SilkS" user "Ref Des/Silkscreen Top")
		(7 "B.SilkS" user "Ref Des/Silkscreen Bottom")
		(1 "F.Mask" user "Board Geometry/Soldermask Top")
		(3 "B.Mask" user "Board Geometry/Soldermask Bottom")
		(17 "Dwgs.User" user "User.Drawings")
		(19 "Cmts.User" user "User.Comments")
		(21 "Eco1.User" user "User.Eco1")
		(23 "Eco2.User" user "User.Eco2")
		(25 "Edge.Cuts" user "Board Geometry/Outline")
		(27 "Margin" user)
		(31 "F.CrtYd" user "Package Geometry/Place Bound Top")
		(29 "B.CrtYd" user "Package Geometry/Place Bound Bottom")
		(35 "F.Fab" user "Ref Des/Assembly Top")
		(33 "B.Fab" user "Ref Des/Assembly Bottom")
	)
	(footprint ""
		(layer "F.Cu")
		(at 51.181 -145.296128)
		(property "Reference" "SR943"
			(at 0 0 0)
			(layer "F.SilkS")
			(hide yes)
			(effects
				(font
					(size 1.27 1.27)
				)
			)
		)
		(property "Value" "4K75R2F-1-GP"
			(at 0.064008 -3.993896 0)
			(unlocked yes)
			(layer "F.Fab")
			(hide yes)
			(effects
				(font
					(size 1.016 1.016)
					(thickness 0.1524)
				)
			)
		)
		(property "Device Type" "R402H16"
			(at 0.064008 -5.517896 0)
			(unlocked yes)
			(layer "F.Fab")
			(hide yes)
			(effects
				(font
					(size 1.016 1.016)
					(thickness 0.1524)
				)
			)
		)
		(duplicate_pad_numbers_are_jumpers no)
		(fp_line
			(start -0.508 -0.9398)
			(end -0.508 0.9398)
			(stroke
				(width 0.1524)
				(type default)
			)
			(layer "F.SilkS")
		)
		(fp_line
			(start 0.508 -0.9398)
			(end -0.508 -0.9398)
			(stroke
				(width 0.1524)
				(type default)
			)
			(layer "F.SilkS")
		)
		(fp_rect
			(start -0.508 0.9398)
			(end 0.508 -0.9398)
			(stroke
				(width 0)
				(type default)
			)
			(fill no)
			(layer "F.CrtYd")
		)
		(fp_rect
			(start -0.508 0.9398)
			(end 0.508 -0.9398)
			(stroke
				(width 0)
				(type default)
			)
			(fill no)
			(layer "F.Fab")
		)
		(pad "1" smd custom
			(at 0 -0.4445)
			(size 0.1397 0.1397)
			(layers "F.Cu" "F.Mask" "F.Paste")
			(net "P3V3_STBY")
			(options
				(clearance outline)
				(anchor circle)
			)
			(primitives
				(gr_poly
					(pts
						(arc
							(start -0.1778 -0.2794)
							(mid -0.249642 -0.249642)
							(end -0.2794 -0.1778)
						)
						(arc
							(start -0.2794 0.1778)
							(mid -0.249642 0.249642)
							(end -0.1778 0.2794)
						)
						(arc
							(start 0.1778 0.2794)
							(mid 0.249642 0.249642)
							(end 0.2794 0.1778)
						)
						(arc
							(start 0.2794 -0.1778)
							(mid 0.249642 -0.249642)
							(end 0.1778 -0.2794)
						)
					)
					(width 0)
					(fill yes)
				)
			)
		)
		(pad "2" smd custom
			(at 0 0.4445)
			(size 0.1397 0.1397)
			(layers "F.Cu" "F.Mask" "F.Paste")
			(net "BMC_FW_DET_BOARD_VER_1")
			(options
				(clearance outline)
				(anchor circle)
			)
			(primitives
				(gr_poly
					(pts
						(arc
							(start -0.1778 -0.2794)
							(mid -0.249642 -0.249642)
							(end -0.2794 -0.1778)
						)
						(arc
							(start -0.2794 0.1778)
							(mid -0.249642 0.249642)
							(end -0.1778 0.2794)
						)
						(arc
							(start 0.1778 0.2794)
							(mid 0.249642 0.249642)
							(end 0.2794 0.1778)
						)
						(arc
							(start 0.2794 -0.1778)
							(mid 0.249642 -0.249642)
							(end 0.1778 -0.2794)
						)
					)
					(width 0)
					(fill yes)
				)
			)
		)
	)
	(footprint ""
		(layer "F.Cu")
		(at 18.796 -143.002)
		(property "Reference" "C201"
			(at 0 0 0)
			(layer "F.SilkS")
			(hide yes)
			(effects
				(font
					(size 1.27 1.27)
				)
			)
		)
		(property "Value" "SC1U10V2KX-4-GP"
			(at 1.1811 -2.7051 0)
			(unlocked yes)
			(layer "F.Fab")
			(hide yes)
			(effects
				(font
					(size 1.016 1.016)
					(thickness 0.1524)
				)
			)
		)
		(property "Device Type" "C402H22"
			(at 1.1811 -4.2291 0)
			(unlocked yes)
			(layer "F.Fab")
			(hide yes)
			(effects
				(font
					(size 1.016 1.016)
					(thickness 0.1524)
				)
			)
		)
		(duplicate_pad_numbers_are_jumpers no)
		(fp_rect
			(start -0.4318 0.9525)
			(end 0.4318 -0.9525)
			(stroke
				(width 0)
				(type default)
			)
			(fill no)
			(layer "F.CrtYd")
		)
		(fp_rect
			(start -0.4318 0.9525)
			(end 0.4318 -0.9525)
			(stroke
				(width 0)
				(type default)
			)
			(fill no)
			(layer "F.Fab")
		)
		(pad "1" smd custom
			(at 0 -0.4445)
			(size 0.1524 0.1524)
			(layers "F.Cu" "F.Mask" "F.Paste")
			(net "V1PLLAV12")
			(options
				(clearance outline)
				(anchor circle)
			)
			(primitives
				(gr_poly
					(pts
						(arc
							(start 0.3048 -0.2032)
							(mid 0.275042 -0.275042)
							(end 0.2032 -0.3048)
						)
						(arc
							(start -0.2032 -0.3048)
							(mid -0.275042 -0.275042)
							(end -0.3048 -0.2032)
						)
						(arc
							(start -0.3048 0.2032)
							(mid -0.275042 0.275042)
							(end -0.2032 0.3048)
						)
						(arc
							(start 0.2032 0.3048)
							(mid 0.275042 0.275042)
							(end 0.3048 0.2032)
						)
					)
					(width 0)
					(fill yes)
				)
			)
		)
		(pad "2" smd custom
			(at 0 0.4445)
			(size 0.1524 0.1524)
			(layers "F.Cu" "F.Mask" "F.Paste")
			(net "GND")
			(options
				(clearance outline)
				(anchor circle)
			)
			(primitives
				(gr_poly
					(pts
						(arc
							(start 0.3048 -0.2032)
							(mid 0.275042 -0.275042)
							(end 0.2032 -0.3048)
						)
						(arc
							(start -0.2032 -0.3048)
							(mid -0.275042 -0.275042)
							(end -0.3048 -0.2032)
						)
						(arc
							(start -0.3048 0.2032)
							(mid -0.275042 0.275042)
							(end -0.2032 0.3048)
						)
						(arc
							(start 0.2032 0.3048)
							(mid 0.275042 0.275042)
							(end 0.3048 0.2032)
						)
					)
					(width 0)
					(fill yes)
				)
			)
		)
	)
	(footprint ""
		(layer "F.Cu")
		(at 301.99203 -212.420454 180)
		(property "Reference" "C74"
			(at 0 0 180)
			(layer "F.SilkS")
			(hide yes)
			(effects
				(font
					(size 1.27 1.27)
				)
			)
		)
		(property "Value" "SCD22U10V2KX-1GP"
			(at 1.1811 -2.7051 180)
			(unlocked yes)
			(layer "F.Fab")
			(hide yes)
			(effects
				(font
					(size 1.016 1.016)
					(thickness 0.1524)
				)
			)
		)
		(property "Device Type" "C402H22"
			(at 1.1811 -4.2291 180)
			(unlocked yes)
			(layer "F.Fab")
			(hide yes)
			(effects
				(font
					(size 1.016 1.016)
					(thickness 0.1524)
				)
			)
		)
		(duplicate_pad_numbers_are_jumpers no)
		(fp_rect
			(start -0.4318 0.9525)
			(end 0.4318 -0.9525)
			(stroke
				(width 0)
				(type default)
			)
			(fill no)
			(layer "F.CrtYd")
		)
		(fp_rect
			(start -0.4318 0.9525)
			(end 0.4318 -0.9525)
			(stroke
				(width 0)
				(type default)
			)
			(fill no)
			(layer "F.Fab")
		)
		(pad "1" smd custom
			(at 0 -0.4445 180)
			(size 0.1524 0.1524)
			(layers "F.Cu" "F.Mask" "F.Paste")
			(net "PCIE_TX_CAP_P26")
			(options
				(clearance outline)
				(anchor circle)
			)
			(primitives
				(gr_poly
					(pts
						(arc
							(start 0.3048 -0.2032)
							(mid 0.275042 -0.275042)
							(end 0.2032 -0.3048)
						)
						(arc
							(start -0.2032 -0.3048)
							(mid -0.275042 -0.275042)
							(end -0.3048 -0.2032)
						)
						(arc
							(start -0.3048 0.2032)
							(mid -0.275042 0.275042)
							(end -0.2032 0.3048)
						)
						(arc
							(start 0.2032 0.3048)
							(mid 0.275042 0.275042)
							(end 0.3048 0.2032)
						)
					)
					(width 0)
					(fill yes)
				)
			)
		)
		(pad "2" smd custom
			(at 0 0.4445 180)
			(size 0.1524 0.1524)
			(layers "F.Cu" "F.Mask" "F.Paste")
			(net "PCIE_TX_P26")
			(options
				(clearance outline)
				(anchor circle)
			)
			(primitives
				(gr_poly
					(pts
						(arc
							(start 0.3048 -0.2032)
							(mid 0.275042 -0.275042)
							(end 0.2032 -0.3048)
						)
						(arc
							(start -0.2032 -0.3048)
							(mid -0.275042 -0.275042)
							(end -0.3048 -0.2032)
						)
						(arc
							(start -0.3048 0.2032)
							(mid -0.275042 0.275042)
							(end -0.2032 0.3048)
						)
						(arc
							(start 0.2032 0.3048)
							(mid 0.275042 0.275042)
							(end 0.3048 0.2032)
						)
					)
					(width 0)
					(fill yes)
				)
			)
		)
	)
	(footprint ""
		(layer "F.Cu")
		(at 339.598 -66.8655 90)
		(property "Reference" "PU3"
			(at 0 0 90)
			(layer "F.SilkS")
			(hide yes)
			(effects
				(font
					(size 1.27 1.27)
				)
			)
		)
		(property "Value" "TPS53355ADQPR-GP"
			(at 4.7498 -5.6896 90)
			(unlocked yes)
			(layer "F.Fab")
			(hide yes)
			(effects
				(font
					(size 1.016 1.016)
					(thickness 0.1524)
				)
			)
		)
		(property "Device Type" "QFN22G6050-G6133H60"
			(at 4.7498 -7.2136 90)
			(unlocked yes)
			(layer "F.Fab")
			(hide yes)
			(effects
				(font
					(size 1.016 1.016)
					(thickness 0.1524)
				)
			)
		)
		(duplicate_pad_numbers_are_jumpers no)
		(fp_line
			(start -2.286 -3.5179)
			(end -3.556 -3.5179)
			(stroke
				(width 0.1524)
				(type default)
			)
			(layer "F.SilkS")
		)
		(fp_line
			(start -3.556 -3.5179)
			(end -3.556 -2.2479)
			(stroke
				(width 0.1524)
				(type default)
			)
			(layer "F.SilkS")
		)
		(fp_line
			(start 0.500126 -3.262122)
			(end 0.500126 -3.770122)
			(stroke
				(width 0.1524)
				(type default)
			)
			(layer "F.SilkS")
		)
		(fp_line
			(start -1.999996 -3.262122)
			(end -1.999996 -4.024122)
			(stroke
				(width 0.1524)
				(type default)
			)
			(layer "F.SilkS")
		)
		(fp_line
			(start -3.556 2.2479)
			(end -3.556 3.5179)
			(stroke
				(width 0.1524)
				(type default)
			)
			(layer "F.SilkS")
		)
		(fp_line
			(start 1.500124 3.262122)
			(end 1.500124 4.024122)
			(stroke
				(width 0.1524)
				(type default)
			)
			(layer "F.SilkS")
		)
		(fp_line
			(start -0.999998 3.262122)
			(end -0.999998 3.770122)
			(stroke
				(width 0.1524)
				(type default)
			)
			(layer "F.SilkS")
		)
		(fp_line
			(start 3.556 3.5179)
			(end 3.556 2.2479)
			(stroke
				(width 0.1524)
				(type default)
			)
			(layer "F.SilkS")
		)
		(fp_line
			(start 2.286 3.5179)
			(end 3.556 3.5179)
			(stroke
				(width 0.1524)
				(type default)
			)
			(layer "F.SilkS")
		)
		(fp_line
			(start -3.556 3.5179)
			(end -2.286 3.5179)
			(stroke
				(width 0.1524)
				(type default)
			)
			(layer "F.SilkS")
		)
		(fp_poly
			(pts
				(xy 3.556 -3.5179) (xy 2.5273 -3.5179) (xy 3.556 -2.4892)
			)
			(stroke
				(width 0)
				(type default)
			)
			(fill yes)
			(layer "F.SilkS")
		)
		(fp_rect
			(start -2.9972 2.5019)
			(end 2.9972 -2.5019)
			(stroke
				(width 0)
				(type default)
			)
			(fill no)
			(layer "F.CrtYd")
		)
		(fp_poly
			(pts
				(xy 3.556 -2.5019) (xy -2.9972 -2.5019) (xy -2.9972 2.5019) (xy 2.9972 2.5019) (xy 2.9972 -2.4892)
				(xy 3.556 -2.4892) (xy 3.556 3.5179) (xy -3.556 3.5179) (xy -3.556 -3.5179) (xy 3.556 -3.5179)
			)
			(stroke
				(width 0)
				(type default)
			)
			(fill no)
			(layer "F.CrtYd")
		)
		(fp_rect
			(start -3.556 3.5179)
			(end 3.556 -3.5179)
			(stroke
				(width 0)
				(type default)
			)
			(fill no)
			(layer "F.Fab")
		)
		(pad "1" smd rect
			(at 2.500122 -2.449322 90)
			(size 0.3048 1.1176)
			(layers "F.Cu" "F.Mask" "F.Paste")
			(net "P0V9_E_VFB")
		)
		(pad "2" smd rect
			(at 1.999996 -2.449322 90)
			(size 0.3048 1.1176)
			(layers "F.Cu" "F.Mask" "F.Paste")
			(net "P0V9_E_EN")
		)
		(pad "3" smd rect
			(at 1.500124 -2.449322 90)
			(size 0.3048 1.1176)
			(layers "F.Cu" "F.Mask" "F.Paste")
			(net "P0V9_E_PG")
		)
		(pad "4" smd rect
			(at 0.999998 -2.449322 90)
			(size 0.3048 1.1176)
			(layers "F.Cu" "F.Mask" "F.Paste")
			(net "P0V9_E_VBST")
		)
		(pad "5" smd rect
			(at 0.500126 -2.449322 90)
			(size 0.3048 1.1176)
			(layers "F.Cu" "F.Mask" "F.Paste")
			(net "Net_2121")
		)
		(pad "6" smd rect
			(at 0 -2.449322 90)
			(size 0.3048 1.1176)
			(layers "F.Cu" "F.Mask" "F.Paste")
			(net "P0V9_E_LX")
		)
		(pad "7" smd rect
			(at -0.500126 -2.449322 90)
			(size 0.3048 1.1176)
			(layers "F.Cu" "F.Mask" "F.Paste")
			(net "P0V9_E_LX")
		)
		(pad "8" smd rect
			(at -0.999998 -2.449322 90)
			(size 0.3048 1.1176)
			(layers "F.Cu" "F.Mask" "F.Paste")
			(net "P0V9_E_LX")
		)
		(pad "9" smd rect
			(at -1.500124 -2.449322 90)
			(size 0.3048 1.1176)
			(layers "F.Cu" "F.Mask" "F.Paste")
			(net "P0V9_E_LX")
		)
		(pad "10" smd rect
			(at -1.999996 -2.449322 90)
			(size 0.3048 1.1176)
			(layers "F.Cu" "F.Mask" "F.Paste")
			(net "P0V9_E_LX")
		)
		(pad "11" smd rect
			(at -2.500122 -2.449322 90)
			(size 0.3048 1.1176)
			(layers "F.Cu" "F.Mask" "F.Paste")
			(net "P0V9_E_LX")
		)
		(pad "12" smd rect
			(at -2.500122 2.449322 90)
			(size 0.3048 1.1176)
			(layers "F.Cu" "F.Mask" "F.Paste")
			(net "P0V9_E_VIN")
		)
		(pad "13" smd rect
			(at -1.999996 2.449322 90)
			(size 0.3048 1.1176)
			(layers "F.Cu" "F.Mask" "F.Paste")
			(net "P0V9_E_VIN")
		)
		(pad "14" smd rect
			(at -1.500124 2.449322 90)
			(size 0.3048 1.1176)
			(layers "F.Cu" "F.Mask" "F.Paste")
			(net "P0V9_E_VIN")
		)
		(pad "15" smd rect
			(at -0.999998 2.449322 90)
			(size 0.3048 1.1176)
			(layers "F.Cu" "F.Mask" "F.Paste")
			(net "P0V9_E_VIN")
		)
		(pad "16" smd rect
			(at -0.500126 2.449322 90)
			(size 0.3048 1.1176)
			(layers "F.Cu" "F.Mask" "F.Paste")
			(net "P0V9_E_VIN")
		)
		(pad "17" smd rect
			(at 0 2.449322 90)
			(size 0.3048 1.1176)
			(layers "F.Cu" "F.Mask" "F.Paste")
			(net "P0V9_E_VIN")
		)
		(pad "18" smd rect
			(at 0.500126 2.449322 90)
			(size 0.3048 1.1176)
			(layers "F.Cu" "F.Mask" "F.Paste")
			(net "P0V9_E_VREG")
		)
		(pad "19" smd rect
			(at 0.999998 2.449322 90)
			(size 0.3048 1.1176)
			(layers "F.Cu" "F.Mask" "F.Paste")
			(net "P0V9_E_VDD")
		)
		(pad "20" smd rect
			(at 1.500124 2.449322 90)
			(size 0.3048 1.1176)
			(layers "F.Cu" "F.Mask" "F.Paste")
			(net "P0V9_E_MODE")
		)
		(pad "21" smd rect
			(at 1.999996 2.449322 90)
			(size 0.3048 1.1176)
			(layers "F.Cu" "F.Mask" "F.Paste")
			(net "P0V9_E_TRIP")
		)
		(pad "22" smd rect
			(at 2.500122 2.449322 90)
			(size 0.3048 1.1176)
			(layers "F.Cu" "F.Mask" "F.Paste")
			(net "P0V9_E_RF")
		)
		(pad "23" smd custom
			(at 0 0 90)
			(size 0.83185 0.83185)
			(layers "F.Cu" "F.Mask" "F.Paste")
			(net "GND")
			(options
				(clearance outline)
				(anchor circle)
			)
			(primitives
				(gr_poly
					(pts
						(xy -2.7813 1.6637) (xy -2.7813 1.2954) (xy -3.048 1.2954) (xy -3.048 0.9525) (xy -2.7813 0.9525)
						(xy -2.7813 -0.9525) (xy -3.048 -0.9525) (xy -3.048 -1.2954) (xy -2.7813 -1.2954) (xy -2.7813 -1.6637)
						(xy 2.7813 -1.6637) (xy 2.7813 -1.2954) (xy 3.048 -1.2954) (xy 3.048 -0.9525) (xy 2.7813 -0.9525)
						(xy 2.7813 0.9525) (xy 3.048 0.9525) (xy 3.048 1.2954) (xy 2.7813 1.2954) (xy 2.7813 1.6637)
					)
					(width 0)
					(fill yes)
				)
			)
		)
	)
	(footprint ""
		(layer "F.Cu")
		(at 70.715124 -183.235092 180)
		(property "Reference" "R516"
			(at 0 0 180)
			(layer "F.SilkS")
			(hide yes)
			(effects
				(font
					(size 1.27 1.27)
				)
			)
		)
		(property "Value" "10KR2F-2-GP"
			(at 0.064008 -3.993896 180)
			(unlocked yes)
			(layer "F.Fab")
			(hide yes)
			(effects
				(font
					(size 1.016 1.016)
					(thickness 0.1524)
				)
			)
		)
		(property "Device Type" "R402H16"
			(at 0.064008 -5.517896 180)
			(unlocked yes)
			(layer "F.Fab")
			(hide yes)
			(effects
				(font
					(size 1.016 1.016)
					(thickness 0.1524)
				)
			)
		)
		(duplicate_pad_numbers_are_jumpers no)
		(fp_line
			(start 0.508 -0.9398)
			(end -0.508 -0.9398)
			(stroke
				(width 0.1524)
				(type default)
			)
			(layer "F.SilkS")
		)
		(fp_line
			(start -0.508 -0.9398)
			(end -0.508 0.9398)
			(stroke
				(width 0.1524)
				(type default)
			)
			(layer "F.SilkS")
		)
		(fp_rect
			(start -0.508 0.9398)
			(end 0.508 -0.9398)
			(stroke
				(width 0)
				(type default)
			)
			(fill no)
			(layer "F.CrtYd")
		)
		(fp_rect
			(start -0.508 0.9398)
			(end 0.508 -0.9398)
			(stroke
				(width 0)
				(type default)
			)
			(fill no)
			(layer "F.Fab")
		)
		(pad "1" smd custom
			(at 0 -0.4445 180)
			(size 0.1397 0.1397)
			(layers "F.Cu" "F.Mask" "F.Paste")
			(net "GND")
			(options
				(clearance outline)
				(anchor circle)
			)
			(primitives
				(gr_poly
					(pts
						(arc
							(start -0.1778 -0.2794)
							(mid -0.249642 -0.249642)
							(end -0.2794 -0.1778)
						)
						(arc
							(start -0.2794 0.1778)
							(mid -0.249642 0.249642)
							(end -0.1778 0.2794)
						)
						(arc
							(start 0.1778 0.2794)
							(mid 0.249642 0.249642)
							(end 0.2794 0.1778)
						)
						(arc
							(start 0.2794 -0.1778)
							(mid 0.249642 -0.249642)
							(end 0.1778 -0.2794)
						)
					)
					(width 0)
					(fill yes)
				)
			)
		)
		(pad "2" smd custom
			(at 0 0.4445 180)
			(size 0.1397 0.1397)
			(layers "F.Cu" "F.Mask" "F.Paste")
			(net "IOEXP1_AD2")
			(options
				(clearance outline)
				(anchor circle)
			)
			(primitives
				(gr_poly
					(pts
						(arc
							(start -0.1778 -0.2794)
							(mid -0.249642 -0.249642)
							(end -0.2794 -0.1778)
						)
						(arc
							(start -0.2794 0.1778)
							(mid -0.249642 0.249642)
							(end -0.1778 0.2794)
						)
						(arc
							(start 0.1778 0.2794)
							(mid 0.249642 0.249642)
							(end 0.2794 0.1778)
						)
						(arc
							(start 0.2794 -0.1778)
							(mid 0.249642 -0.249642)
							(end 0.1778 -0.2794)
						)
					)
					(width 0)
					(fill yes)
				)
			)
		)
	)
)
